FILE_TYPE = CONNECTIVITY;
{Allegro Design Entry HDL 16.6-p007 (v16-6-112F) 10/10/2012}
"PAGE_NUMBER" = 158;
0"NC";
1"P3V3_STBY\g";
2"GND\g";
3"GND\g";
4"GND\g";
5"P3V3_STBY\g";
6"P3V3_STBY\g";
7"GND\g";
8"FM_UARTSW_MSB_N";
9"SP2_BMC_CM_UART_TX";
10"FM_UARTSW_MSB_R_N";
11"SP1_BMC_HOST_UART_TX";
12"UART_BMC_TXD5";
13"SPA_MID_DBG_RX";
14"FM_UARTSW_LSB_N";
15"SPA_MID_DBG_TX";
16"FM_UARTSW_LSB_N";
17"FM_UARTSW_MSB_N";
18"FM_UARTSW_MSB_N";
19"SP2_BMC_CM_UART_TX_R";
20"SP1_BMC_HOST_UART_RX";
21"UART_BMC_RXD5";
22"SP2_BMC_CM_UART_RX";
23"SP2_BMC_CM_UART_RX_R";
24"SP2_BMC_CM_UART_RX_R1";
25"UART_MUX_IN_R";
26"SP2_BMC_CM_UART_TX_R1";
27"FM_UARTSW_LSB_N";
28"FM_UARTSW_LSB_R_N";
29"UART_MUX_OUT_R";
%"RES"
"1","(-2650,1525)","0","mstr_discrete","I100";
;
CDS_SEC"1"
ROOM"UART_MUX"
CDS_LOCATION"R9F24"
SEC"1"
SEC_TYPE"0402"
BOM_COST"DEBUG"
CDS_LIB"mstr_discrete"
LOCATION"R9F24"
TOLERANCE"5%"
PART_NUMBER"G21497-005"
PACK_TYPE"0402"
VALUE"0.0"
WATTAGE"1/16W"
MATERIAL"EMPTY";
"B"
$PN"2"22;
"A"
$PN"1"13;
%"LED"
"3","(-5725,3200)","0","mstr_discrete","I130";
;
CDS_SEC"1"
PACK_TYPE"A1LF"
ROOM"UART_MUX"
CDS_LOCATION"DS9A4"
SEC"1"
SEC_TYPE"A1LF"
BOM_COST"DEBUG"
CDS_LIB"mstr_discrete"
LOCATION"DS9A4"
MATERIAL"IC"
COLOR"GREEN"
PART_NUMBER"D14725-022";
"A"
$PN"1"28;
"C"
$PN"2"27;
%"RES"
"1","(-4875,3200)","0","mstr_discrete","I131";
;
CDS_SEC"1"
ROOM"UART_MUX"
SEC_TYPE"0402"
BOM_COST"DEBUG"
SEC"1"
CDS_LOCATION"R1L43"
CDS_LIB"mstr_discrete"
TOLERANCE"5%"
LOCATION"R1L43"
VALUE"330"
MATERIAL"CHIP"
PACK_TYPE"0402"
PART_NUMBER"G21497-028"
WATTAGE"1/16W";
"B"
$PN"2"1;
"A"
$PN"1"28;
%"LED"
"3","(-5725,3600)","0","mstr_discrete","I134";
;
CDS_SEC"1"
PACK_TYPE"A1LF"
ROOM"UART_MUX"
SEC"1"
SEC_TYPE"A1LF"
BOM_COST"DEBUG"
CDS_LOCATION"DS9A7"
CDS_LIB"mstr_discrete"
PART_NUMBER"D14725-022"
LOCATION"DS9A7"
MATERIAL"IC"
COLOR"GREEN";
"A"
$PN"1"10;
"C"
$PN"2"8;
%"P3V3_STBY"
"1","(-4400,3850)","0","mstr_symbols","I135";
;
SIZE"1B"
CDS_LIB"mstr_symbols"
BODY_TYPE"PLUMBING"
VOLTAGE"3.3V"
HDL_POWER"P3V3_STBY";
"G\NAC"1;
%"RES"
"1","(-4875,3600)","0","mstr_discrete","I136";
;
CDS_SEC"1"
ROOM"UART_MUX"
BOM_COST"DEBUG"
CDS_LOCATION"R1L44"
SEC_TYPE"0402"
CDS_LIB"mstr_discrete"
SEC"1"
TOLERANCE"5%"
PACK_TYPE"0402"
LOCATION"R1L44"
MATERIAL"CHIP"
VALUE"330"
WATTAGE"1/16W"
PART_NUMBER"G21497-028";
"B"
$PN"2"1;
"A"
$PN"1"10;
%"RES"
"1","(-3125,3750)","0","mstr_discrete","I148";
;
CDS_SEC"1"
$SEC"1"
CDS_LOCATION"R9F65"
ROOM"UART_MUX"
BOM_COST"DEBUG"
CDS_LIB"mstr_discrete"
PART_NUMBER"G21497-005"
VALUE"0.0"
LOCATION"R9F65"
WATTAGE"1/16W"
TOLERANCE"5%"
MATERIAL"CHIP"
PACK_TYPE"0402";
"B"
$PN"2"19;
"A"
$PN"1"26;
%"RES"
"1","(-1400,850)","0","mstr_discrete","I149";
;
CDS_LOCATION"R9F68"
CDS_SEC"1"
$SEC"1"
CDS_LIB"mstr_discrete"
BOM_COST"DEBUG"
ROOM"UART_MUX"
PART_NUMBER"G21497-005"
LOCATION"R9F68"
WATTAGE"1/16W"
VALUE"0.0"
TOLERANCE"5%"
MATERIAL"EMPTY"
PACK_TYPE"0402";
"B"
$PN"2"22;
"A"
$PN"1"23;
%"RES"
"1","(-1250,1775)","0","mstr_discrete","I150";
;
CDS_LOCATION"R9F69"
SEC"1"
SEC_TYPE"0402"
BOM_COST"DEBUG"
ROOM"UART_MUX"
CDS_LIB"mstr_discrete"
CDS_SEC"1"
PART_NUMBER"G21497-005"
LOCATION"R9F69"
VALUE"0.0"
MATERIAL"CHIP"
PACK_TYPE"0402"
TOLERANCE"5%"
WATTAGE"1/16W";
"B"
$PN"2"24;
"A"
$PN"1"23;
%"RES"
"1","(-3150,2575)","0","mstr_discrete","I152";
;
CDS_SEC"1"
$SEC"1"
CDS_LOCATION"R9F66"
CDS_LIB"mstr_discrete"
BOM_COST"DEBUG"
ROOM"UART_MUX"
LOCATION"R9F66"
TOLERANCE"5%"
VALUE"0.0"
WATTAGE"1/16W"
PACK_TYPE"0402"
MATERIAL"EMPTY"
PART_NUMBER"G21497-005";
"B"
$PN"2"19;
"A"
$PN"1"9;
%"CAP_A"
"1","(-1775,2950)","0","dev_discrete","I70";
;
ROOM"UART_MUX"
SEC"1"
SEC_TYPE"0402V"
CDS_SEC"1"
BOM_COST"DEBUG"
CDS_LOCATION"C1T10"
CDS_LIB"dev_discrete"
LOCATION"C1T10"
VALUE"0.1UF"
TOLERANCE"10%"
VOLTAGE"16V"
MATERIAL"X7R"
PACK_TYPE"0402V"
PART_NUMBER"A36096-030";
"B"
$PN"2"2;
"A"
$PN"1"5;
%"GND"
"1","(-1775,2725)","0","mstr_symbols","I72";
;
HDL_POWER"GND"
CDS_LIB"mstr_symbols"
SIZE"1B"
VOLTAGE"0.0V"
BODY_TYPE"PLUMBING";
"A\NAC"2;
%"FSA3357"
"1","(-2275,2575)","2","mstr_analog","I74";
;
CDS_SEC"1"
BOM_COST"DEBUG"
PACK_TYPE"SM"
ROOM"UART_MUX"
CDS_LOCATION"U9F2"
SEC"1"
SEC_TYPE"SM"
CDS_LIB"mstr_analog"
PART_NUMBER"C63273-001"
LOCATION"U9F2"
MATERIAL"IC";
"VCC"
$PN"8"5;
"GND"
$PN"4"3;
"B0"
$PN"1"19;
"B1"
$PN"2"12;
"B2"
$PN"3"11;
"A"
$PN"7"29;
"S2"
$PN"5"18;
"S1"
$PN"6"14;
%"FSA3357"
"1","(-2650,850)","0","mstr_analog","I75";
;
CDS_SEC"1"
PACK_TYPE"SM"
ROOM"UART_MUX"
BOM_COST"DEBUG"
CDS_LOCATION"U9F1"
SEC"1"
SEC_TYPE"SM"
CDS_LIB"mstr_analog"
MATERIAL"IC"
LOCATION"U9F1"
PART_NUMBER"C63273-001";
"VCC"
$PN"8"6;
"GND"
$PN"4"4;
"B0"
$PN"1"23;
"B1"
$PN"2"21;
"B2"
$PN"3"20;
"A"
$PN"7"25;
"S2"
$PN"5"17;
"S1"
$PN"6"16;
%"GND"
"1","(-2625,2125)","0","mstr_symbols","I76";
;
SIZE"1B"
VOLTAGE"0.0V"
HDL_POWER"GND"
BODY_TYPE"PLUMBING"
CDS_LIB"mstr_symbols";
"A\NAC"3;
%"GND"
"1","(-2325,425)","0","mstr_symbols","I77";
;
HDL_POWER"GND"
VOLTAGE"0.0V"
BODY_TYPE"PLUMBING"
SIZE"1B"
CDS_LIB"mstr_symbols";
"A\NAC"4;
%"P3V3_STBY"
"1","(-1950,3150)","0","mstr_symbols","I78";
;
SIZE"1B"
CDS_LIB"mstr_symbols"
BODY_TYPE"PLUMBING"
VOLTAGE"3.3V"
HDL_POWER"P3V3_STBY";
"G\NAC"5;
%"P3V3_STBY"
"1","(-3100,1425)","0","mstr_symbols","I79";
;
SIZE"1B"
CDS_LIB"mstr_symbols"
BODY_TYPE"PLUMBING"
VOLTAGE"3.3V"
HDL_POWER"P3V3_STBY";
"G\NAC"6;
%"RES"
"1","(-3625,900)","0","mstr_discrete","I86";
;
CDS_SEC"1"
BOM_COST"DEBUG"
SEC"1"
SEC_TYPE"0402"
ROOM"UART_MUX"
CDS_LIB"mstr_discrete"
CDS_LOCATION"R9F25"
WATTAGE"1/16W"
MATERIAL"CHIP"
PART_NUMBER"G21796-017"
TOLERANCE"1%"
LOCATION"R9F25"
VALUE"100.0"
PACK_TYPE"0402";
"B"
$PN"2"25;
"A"
$PN"1"13;
%"RES"
"1","(-1325,2625)","0","mstr_discrete","I91";
;
CDS_SEC"1"
SEC_TYPE"0402"
SEC"1"
BOM_COST"DEBUG"
CDS_LOCATION"R9F27"
CDS_LIB"mstr_discrete"
ROOM"UART_MUX"
PART_NUMBER"G21497-005"
TOLERANCE"5%"
PACK_TYPE"0402"
LOCATION"R9F27"
VALUE"0.0"
WATTAGE"1/16W"
MATERIAL"CHIP";
"B"
$PN"2"15;
"A"
$PN"1"29;
%"CAP_A"
"1","(-3475,1200)","0","dev_discrete","I97";
;
ROOM"UART_MUX"
SEC"1"
CDS_LOCATION"C1T11"
CDS_SEC"1"
BOM_COST"DEBUG"
SEC_TYPE"0402V"
CDS_LIB"dev_discrete"
PART_NUMBER"A36096-030"
LOCATION"C1T11"
VALUE"0.1UF"
TOLERANCE"10%"
MATERIAL"X7R"
VOLTAGE"16V"
PACK_TYPE"0402V";
"B"
$PN"2"7;
"A"
$PN"1"6;
%"GND"
"1","(-3475,1000)","0","mstr_symbols","I98";
;
HDL_POWER"GND"
CDS_LIB"mstr_symbols"
VOLTAGE"0.0V"
SIZE"1B"
BODY_TYPE"PLUMBING";
"A\NAC"7;
%"RES"
"1","(-1900,3450)","0","mstr_discrete","I99";
;
CDS_SEC"1"
ROOM"UART_MUX"
BOM_COST"DEBUG"
SEC_TYPE"0402"
SEC"1"
CDS_LOCATION"R9F26"
CDS_LIB"mstr_discrete"
WATTAGE"1/16W"
PART_NUMBER"G21497-005"
VALUE"0.0"
TOLERANCE"5%"
MATERIAL"EMPTY"
PACK_TYPE"0402"
LOCATION"R9F26";
"B"
$PN"2"15;
"A"
$PN"1"9;
END.
